FILE_TYPE = CONNECTIVITY;
{Allegro Design Entry HDL 17.4-2019 S026 (4007227) 1/17/2022}
"PAGE_NUMBER" = 140;
0"NC";
END.
